FILE_TYPE = CONNECTIVITY;
{Allegro Design Entry HDL 16.6-p007 (v16-6-112F) 10/10/2012}
"PAGE_NUMBER" = 4;
0"NC";
END.
